# T6G (Grand Teton) — schematic netlist excerpt (pin names and nets, part order shuffled) for the footprints in the layout excerpt that follows; sources: Cadence DE-HDL packaged netlist, KiCad conversion of 04192023_DAF0TMB3IC0_F0TG_MB_C_brd_V02_OCP.brd

C728  Q_CAP_DIFFBUS  DIFF BUS_0.22UF 6.3V 20% X6S  pkg C0201  page 66 : \1\ = P5E_CPU1_P1_TX_C_DN<6> ; \2\ = P5E_CPU1_P1_TX_DN<6>
R1134  Q_RES  0 5% CHIP  pkg 0402LF  page 136 : A = P12V_OCP_SFF_BUF_EN ; B = P12V_OCP_SFF_BUF_EN_R
PC546  Q_CAP  2.2UF 10V 10% X6S  pkg C0402  page 195 : A = PVDDCR_CPU0_P0_VCC3 ; B = GND

(kicad_pcb
	(version 20260206)
	(generator "pcbnew")
	(generator_version "10.0")
	(general
		(thickness 1.6)
		(legacy_teardrops no)
	)
	(paper "A4")
	(title_block
		(title "04192023_DAF0TMB3IC0_F0TG_MB_C_brd_V02_OCP.brd")
		(comment 1 "Grand Teton / footprints 1069-1071 of 8354")
	)
	(layers
		(0 "F.Cu" signal "TOP")
		(4 "In1.Cu" signal "GND")
		(6 "In2.Cu" signal "IN1")
		(8 "In3.Cu" signal "GND1")
		(10 "In4.Cu" signal "IN2")
		(12 "In5.Cu" signal "GND2")
		(14 "In6.Cu" signal "IN3")
		(16 "In7.Cu" signal "GND3")
		(18 "In8.Cu" signal "VCC")
		(20 "In9.Cu" signal "VCC1")
		(22 "In10.Cu" signal "GND4")
		(24 "In11.Cu" signal "IN4")
		(26 "In12.Cu" signal "GND5")
		(28 "In13.Cu" signal "IN5")
		(30 "In14.Cu" signal "GND6")
		(32 "In15.Cu" signal "IN6")
		(34 "In16.Cu" signal "GND7")
		(2 "B.Cu" signal "BOTTOM")
		(9 "F.Adhes" user "F.Adhesive")
		(11 "B.Adhes" user "B.Adhesive")
		(13 "F.Paste" user "Package Geometry/Pastemask Top")
		(15 "B.Paste" user "Package Geometry/Pastemask Bottom")
		(5 "F.SilkS" user "Ref Des/Silkscreen Top")
		(7 "B.SilkS" user "Ref Des/Silkscreen Bottom")
		(1 "F.Mask" user "Board Geometry/Soldermask Top")
		(3 "B.Mask" user "Board Geometry/Soldermask Bottom")
		(17 "Dwgs.User" user "User.Drawings")
		(19 "Cmts.User" user "User.Comments")
		(21 "Eco1.User" user "User.Eco1")
		(23 "Eco2.User" user "User.Eco2")
		(25 "Edge.Cuts" user "Board Geometry/Outline")
		(27 "Margin" user)
		(31 "F.CrtYd" user "Package Geometry/Place Bound Top")
		(29 "B.CrtYd" user "Package Geometry/Place Bound Bottom")
		(35 "F.Fab" user "Ref Des/Assembly Top")
		(33 "B.Fab" user "Ref Des/Assembly Bottom")
	)
	(footprint ""
		(layer "F.Cu")
		(at 384.760978 -180.078634 -90)
		(property "Reference" "PC546"
			(at 0 0 270)
			(layer "F.SilkS")
			(hide yes)
			(effects
				(font
					(size 1.27 1.27)
				)
			)
		)
		(property "Value" ""
			(at 0 0 270)
			(layer "F.Fab")
			(effects
				(font
					(size 1.27 1.27)
				)
			)
		)
		(duplicate_pad_numbers_are_jumpers no)
		(fp_line
			(start -0.7874 0.4064)
			(end -0.7874 -0.4064)
			(stroke
				(width 0.1524)
				(type default)
			)
			(layer "F.SilkS")
		)
		(fp_line
			(start -0.362966 0.4064)
			(end -0.7874 0.4064)
			(stroke
				(width 0.1524)
				(type default)
			)
			(layer "F.SilkS")
		)
		(fp_line
			(start 0.7874 0.4064)
			(end 0.500634 0.4064)
			(stroke
				(width 0.1524)
				(type default)
			)
			(layer "F.SilkS")
		)
		(fp_line
			(start -0.7874 -0.4064)
			(end 0.7874 -0.4064)
			(stroke
				(width 0.1524)
				(type default)
			)
			(layer "F.SilkS")
		)
		(fp_line
			(start 0.7874 -0.4064)
			(end 0.7874 0.4064)
			(stroke
				(width 0.1524)
				(type default)
			)
			(layer "F.SilkS")
		)
		(fp_line
			(start -0.67945 0.3048)
			(end -0.67945 -0.305054)
			(stroke
				(width 0.1)
				(type default)
			)
			(layer "F.Fab")
		)
		(fp_line
			(start -0.12065 0.3048)
			(end -0.67945 0.3048)
			(stroke
				(width 0.1)
				(type default)
			)
			(layer "F.Fab")
		)
		(fp_line
			(start 0.120396 0.3048)
			(end 0.120396 0.2794)
			(stroke
				(width 0.1)
				(type default)
			)
			(layer "F.Fab")
		)
		(fp_line
			(start 0.67945 0.3048)
			(end 0.120396 0.3048)
			(stroke
				(width 0.1)
				(type default)
			)
			(layer "F.Fab")
		)
		(fp_line
			(start -0.12065 0.2794)
			(end -0.12065 0.3048)
			(stroke
				(width 0.1)
				(type default)
			)
			(layer "F.Fab")
		)
		(fp_line
			(start 0.120396 0.2794)
			(end -0.12065 0.2794)
			(stroke
				(width 0.1)
				(type default)
			)
			(layer "F.Fab")
		)
		(fp_line
			(start -0.12065 -0.2794)
			(end 0.12065 -0.2794)
			(stroke
				(width 0.1)
				(type default)
			)
			(layer "F.Fab")
		)
		(fp_line
			(start 0.12065 -0.2794)
			(end 0.12065 -0.3048)
			(stroke
				(width 0.1)
				(type default)
			)
			(layer "F.Fab")
		)
		(fp_line
			(start 0.12065 -0.3048)
			(end 0.67945 -0.3048)
			(stroke
				(width 0.1)
				(type default)
			)
			(layer "F.Fab")
		)
		(fp_line
			(start 0.67945 -0.3048)
			(end 0.67945 0.3048)
			(stroke
				(width 0.1)
				(type default)
			)
			(layer "F.Fab")
		)
		(fp_line
			(start -0.67945 -0.305054)
			(end -0.12065 -0.305054)
			(stroke
				(width 0.1)
				(type default)
			)
			(layer "F.Fab")
		)
		(fp_line
			(start -0.12065 -0.305054)
			(end -0.12065 -0.2794)
			(stroke
				(width 0.1)
				(type default)
			)
			(layer "F.Fab")
		)
		(pad "1" smd circle
			(at -0.40005 0 270)
			(size 0 0)
			(layers "F.Cu" "F.Mask" "F.Paste")
			(net "PVDDCR_CPU0_P0_VCC3")
		)
		(pad "2" smd circle
			(at 0.40005 0 270)
			(size 0 0)
			(layers "F.Cu" "F.Mask" "F.Paste")
			(net "GND")
		)
	)
	(footprint ""
		(layer "F.Cu")
		(at 84.940902 -370.57203 -90)
		(property "Reference" "C728"
			(at 0 0 270)
			(layer "F.SilkS")
			(hide yes)
			(effects
				(font
					(size 1.27 1.27)
				)
			)
		)
		(property "Value" ""
			(at 0 0 270)
			(layer "F.Fab")
			(effects
				(font
					(size 1.27 1.27)
				)
			)
		)
		(duplicate_pad_numbers_are_jumpers no)
		(fp_line
			(start -0.299974 0.150114)
			(end -0.299974 -0.150114)
			(stroke
				(width 0.1)
				(type default)
			)
			(layer "F.Fab")
		)
		(fp_line
			(start 0.299974 0.150114)
			(end -0.299974 0.150114)
			(stroke
				(width 0.1)
				(type default)
			)
			(layer "F.Fab")
		)
		(fp_line
			(start -0.299974 -0.150114)
			(end 0.299974 -0.150114)
			(stroke
				(width 0.1)
				(type default)
			)
			(layer "F.Fab")
		)
		(fp_line
			(start 0.299974 -0.150114)
			(end 0.299974 0.150114)
			(stroke
				(width 0.1)
				(type default)
			)
			(layer "F.Fab")
		)
		(pad "1" smd rect
			(at -0.2667 0 270)
			(size 0.3048 0.381)
			(layers "F.Cu" "F.Mask" "F.Paste")
			(net "P5E_CPU1_P1_TX_C_DN<6>")
		)
		(pad "2" smd rect
			(at 0.2667 0 270)
			(size 0.3048 0.381)
			(layers "F.Cu" "F.Mask" "F.Paste")
			(net "P5E_CPU1_P1_TX_DN<6>")
		)
	)
	(footprint ""
		(layer "F.Cu")
		(at 150.814532 -106.73207 -90)
		(property "Reference" "R1134"
			(at 0 0 270)
			(layer "F.SilkS")
			(hide yes)
			(effects
				(font
					(size 1.27 1.27)
				)
			)
		)
		(property "Value" ""
			(at 0 0 270)
			(layer "F.Fab")
			(effects
				(font
					(size 1.27 1.27)
				)
			)
		)
		(duplicate_pad_numbers_are_jumpers no)
		(fp_line
			(start -0.7874 0.4064)
			(end -0.7874 -0.4064)
			(stroke
				(width 0.1524)
				(type default)
			)
			(layer "F.SilkS")
		)
		(fp_line
			(start 0.7874 0.4064)
			(end -0.7874 0.4064)
			(stroke
				(width 0.1524)
				(type default)
			)
			(layer "F.SilkS")
		)
		(fp_line
			(start -0.7874 -0.4064)
			(end 0.7874 -0.4064)
			(stroke
				(width 0.1524)
				(type default)
			)
			(layer "F.SilkS")
		)
		(fp_line
			(start 0.7874 -0.4064)
			(end 0.7874 0.4064)
			(stroke
				(width 0.1524)
				(type default)
			)
			(layer "F.SilkS")
		)
		(fp_line
			(start -0.67945 0.3048)
			(end -0.67945 -0.305054)
			(stroke
				(width 0.1)
				(type default)
			)
			(layer "F.Fab")
		)
		(fp_line
			(start -0.12065 0.3048)
			(end -0.67945 0.3048)
			(stroke
				(width 0.1)
				(type default)
			)
			(layer "F.Fab")
		)
		(fp_line
			(start 0.120396 0.3048)
			(end 0.120396 0.2794)
			(stroke
				(width 0.1)
				(type default)
			)
			(layer "F.Fab")
		)
		(fp_line
			(start 0.67945 0.3048)
			(end 0.120396 0.3048)
			(stroke
				(width 0.1)
				(type default)
			)
			(layer "F.Fab")
		)
		(fp_line
			(start -0.12065 0.2794)
			(end -0.12065 0.3048)
			(stroke
				(width 0.1)
				(type default)
			)
			(layer "F.Fab")
		)
		(fp_line
			(start 0.120396 0.2794)
			(end -0.12065 0.2794)
			(stroke
				(width 0.1)
				(type default)
			)
			(layer "F.Fab")
		)
		(fp_line
			(start -0.12065 -0.2794)
			(end 0.12065 -0.2794)
			(stroke
				(width 0.1)
				(type default)
			)
			(layer "F.Fab")
		)
		(fp_line
			(start 0.12065 -0.2794)
			(end 0.12065 -0.3048)
			(stroke
				(width 0.1)
				(type default)
			)
			(layer "F.Fab")
		)
		(fp_line
			(start 0.12065 -0.3048)
			(end 0.67945 -0.3048)
			(stroke
				(width 0.1)
				(type default)
			)
			(layer "F.Fab")
		)
		(fp_line
			(start 0.67945 -0.3048)
			(end 0.67945 0.3048)
			(stroke
				(width 0.1)
				(type default)
			)
			(layer "F.Fab")
		)
		(fp_line
			(start -0.67945 -0.305054)
			(end -0.12065 -0.305054)
			(stroke
				(width 0.1)
				(type default)
			)
			(layer "F.Fab")
		)
		(fp_line
			(start -0.12065 -0.305054)
			(end -0.12065 -0.2794)
			(stroke
				(width 0.1)
				(type default)
			)
			(layer "F.Fab")
		)
		(pad "1" smd circle
			(at -0.40005 0 270)
			(size 0 0)
			(layers "F.Cu" "F.Mask" "F.Paste")
			(net "P12V_OCP_SFF_BUF_EN")
		)
		(pad "2" smd circle
			(at 0.40005 0 270)
			(size 0 0)
			(layers "F.Cu" "F.Mask" "F.Paste")
			(net "P12V_OCP_SFF_BUF_EN_R")
		)
	)
)
